(kicad_pcb
	(version 20260206)
	(generator "pcbnew")
	(generator_version "10.0")
	(general
		(thickness 1.6)
		(legacy_teardrops no)
	)
	(paper "A4")
	(title_block
		(title "01162023_DA0F0TEBIF0_F0T_Expander_BD_F_brd_V02_OCP.brd")
		(comment 1 "Grand Teton / footprints 5351-5357 of 9728")
	)
	(layers
		(0 "F.Cu" signal "TOP")
		(4 "In1.Cu" signal "GND")
		(6 "In2.Cu" signal "VCC")
		(8 "In3.Cu" signal "VCC1")
		(10 "In4.Cu" signal "GND1")
		(12 "In5.Cu" signal "IN1")
		(14 "In6.Cu" signal "GND2")
		(16 "In7.Cu" signal "IN2")
		(18 "In8.Cu" signal "GND3")
		(20 "In9.Cu" signal "IN3")
		(22 "In10.Cu" signal "GND4")
		(24 "In11.Cu" signal "IN4")
		(26 "In12.Cu" signal "GND5")
		(28 "In13.Cu" signal "IN5")
		(30 "In14.Cu" signal "GND6")
		(32 "In15.Cu" signal "IN6")
		(34 "In16.Cu" signal "GND7")
		(2 "B.Cu" signal "BOTTOM")
		(9 "F.Adhes" user "F.Adhesive")
		(11 "B.Adhes" user "B.Adhesive")
		(13 "F.Paste" user "Package Geometry/Pastemask Top")
		(15 "B.Paste" user "Package Geometry/Pastemask Bottom")
		(5 "F.SilkS" user "Ref Des/Silkscreen Top")
		(7 "B.SilkS" user "Ref Des/Silkscreen Bottom")
		(1 "F.Mask" user "Board Geometry/Soldermask Top")
		(3 "B.Mask" user "Board Geometry/Soldermask Bottom")
		(17 "Dwgs.User" user "User.Drawings")
		(19 "Cmts.User" user "User.Comments")
		(21 "Eco1.User" user "User.Eco1")
		(23 "Eco2.User" user "User.Eco2")
		(25 "Edge.Cuts" user "Board Geometry/Outline")
		(27 "Margin" user)
		(31 "F.CrtYd" user "Package Geometry/Place Bound Top")
		(29 "B.CrtYd" user "Package Geometry/Place Bound Bottom")
		(35 "F.Fab" user "Ref Des/Assembly Top")
		(33 "B.Fab" user "Ref Des/Assembly Bottom")
	)
	(footprint ""
		(layer "F.Cu")
		(at 30.715204 -59.546236 90)
		(property "Reference" "C2887"
			(at 0 0 90)
			(layer "F.SilkS")
			(hide yes)
			(effects
				(font
					(size 1.27 1.27)
				)
			)
		)
		(property "Value" ""
			(at 0 0 90)
			(layer "F.Fab")
			(effects
				(font
					(size 1.27 1.27)
				)
			)
		)
		(duplicate_pad_numbers_are_jumpers no)
		(fp_line
			(start 0.7874 -0.4064)
			(end 0.7874 0.4064)
			(stroke
				(width 0.1524)
				(type default)
			)
			(layer "F.SilkS")
		)
		(fp_line
			(start -0.7874 -0.4064)
			(end 0.7874 -0.4064)
			(stroke
				(width 0.1524)
				(type default)
			)
			(layer "F.SilkS")
		)
		(fp_line
			(start 0.7874 0.4064)
			(end -0.7874 0.4064)
			(stroke
				(width 0.1524)
				(type default)
			)
			(layer "F.SilkS")
		)
		(fp_line
			(start -0.7874 0.4064)
			(end -0.7874 -0.4064)
			(stroke
				(width 0.1524)
				(type default)
			)
			(layer "F.SilkS")
		)
		(fp_line
			(start -0.12065 -0.305054)
			(end -0.12065 -0.2794)
			(stroke
				(width 0.1)
				(type default)
			)
			(layer "F.Fab")
		)
		(fp_line
			(start -0.67945 -0.305054)
			(end -0.12065 -0.305054)
			(stroke
				(width 0.1)
				(type default)
			)
			(layer "F.Fab")
		)
		(fp_line
			(start 0.67945 -0.3048)
			(end 0.67945 0.3048)
			(stroke
				(width 0.1)
				(type default)
			)
			(layer "F.Fab")
		)
		(fp_line
			(start 0.12065 -0.3048)
			(end 0.67945 -0.3048)
			(stroke
				(width 0.1)
				(type default)
			)
			(layer "F.Fab")
		)
		(fp_line
			(start 0.12065 -0.2794)
			(end 0.12065 -0.3048)
			(stroke
				(width 0.1)
				(type default)
			)
			(layer "F.Fab")
		)
		(fp_line
			(start -0.12065 -0.2794)
			(end 0.12065 -0.2794)
			(stroke
				(width 0.1)
				(type default)
			)
			(layer "F.Fab")
		)
		(fp_line
			(start 0.120396 0.2794)
			(end -0.12065 0.2794)
			(stroke
				(width 0.1)
				(type default)
			)
			(layer "F.Fab")
		)
		(fp_line
			(start -0.12065 0.2794)
			(end -0.12065 0.3048)
			(stroke
				(width 0.1)
				(type default)
			)
			(layer "F.Fab")
		)
		(fp_line
			(start 0.67945 0.3048)
			(end 0.120396 0.3048)
			(stroke
				(width 0.1)
				(type default)
			)
			(layer "F.Fab")
		)
		(fp_line
			(start 0.120396 0.3048)
			(end 0.120396 0.2794)
			(stroke
				(width 0.1)
				(type default)
			)
			(layer "F.Fab")
		)
		(fp_line
			(start -0.12065 0.3048)
			(end -0.67945 0.3048)
			(stroke
				(width 0.1)
				(type default)
			)
			(layer "F.Fab")
		)
		(fp_line
			(start -0.67945 0.3048)
			(end -0.67945 -0.305054)
			(stroke
				(width 0.1)
				(type default)
			)
			(layer "F.Fab")
		)
		(pad "1" smd circle
			(at -0.40005 0 90)
			(size 0 0)
			(layers "F.Cu" "F.Mask" "F.Paste")
			(net "SSD1_AUX_P3V3_EN_R")
		)
		(pad "2" smd circle
			(at 0.40005 0 90)
			(size 0 0)
			(layers "F.Cu" "F.Mask" "F.Paste")
			(net "GND")
		)
	)
	(footprint ""
		(layer "F.Cu")
		(at 56.947308 -36.686998 90)
		(property "Reference" "C204"
			(at 0 0 90)
			(layer "F.SilkS")
			(hide yes)
			(effects
				(font
					(size 1.27 1.27)
				)
			)
		)
		(property "Value" ""
			(at 0 0 90)
			(layer "F.Fab")
			(effects
				(font
					(size 1.27 1.27)
				)
			)
		)
		(duplicate_pad_numbers_are_jumpers no)
		(fp_line
			(start 0.7874 -0.4064)
			(end 0.7874 0.4064)
			(stroke
				(width 0.1524)
				(type default)
			)
			(layer "F.SilkS")
		)
		(fp_line
			(start -0.7874 -0.4064)
			(end 0.7874 -0.4064)
			(stroke
				(width 0.1524)
				(type default)
			)
			(layer "F.SilkS")
		)
		(fp_line
			(start 0.7874 0.4064)
			(end -0.7874 0.4064)
			(stroke
				(width 0.1524)
				(type default)
			)
			(layer "F.SilkS")
		)
		(fp_line
			(start -0.7874 0.4064)
			(end -0.7874 -0.4064)
			(stroke
				(width 0.1524)
				(type default)
			)
			(layer "F.SilkS")
		)
		(fp_line
			(start -0.12065 -0.305054)
			(end -0.12065 -0.2794)
			(stroke
				(width 0.1)
				(type default)
			)
			(layer "F.Fab")
		)
		(fp_line
			(start -0.67945 -0.305054)
			(end -0.12065 -0.305054)
			(stroke
				(width 0.1)
				(type default)
			)
			(layer "F.Fab")
		)
		(fp_line
			(start 0.67945 -0.3048)
			(end 0.67945 0.3048)
			(stroke
				(width 0.1)
				(type default)
			)
			(layer "F.Fab")
		)
		(fp_line
			(start 0.12065 -0.3048)
			(end 0.67945 -0.3048)
			(stroke
				(width 0.1)
				(type default)
			)
			(layer "F.Fab")
		)
		(fp_line
			(start 0.12065 -0.2794)
			(end 0.12065 -0.3048)
			(stroke
				(width 0.1)
				(type default)
			)
			(layer "F.Fab")
		)
		(fp_line
			(start -0.12065 -0.2794)
			(end 0.12065 -0.2794)
			(stroke
				(width 0.1)
				(type default)
			)
			(layer "F.Fab")
		)
		(fp_line
			(start 0.120396 0.2794)
			(end -0.12065 0.2794)
			(stroke
				(width 0.1)
				(type default)
			)
			(layer "F.Fab")
		)
		(fp_line
			(start -0.12065 0.2794)
			(end -0.12065 0.3048)
			(stroke
				(width 0.1)
				(type default)
			)
			(layer "F.Fab")
		)
		(fp_line
			(start 0.67945 0.3048)
			(end 0.120396 0.3048)
			(stroke
				(width 0.1)
				(type default)
			)
			(layer "F.Fab")
		)
		(fp_line
			(start 0.120396 0.3048)
			(end 0.120396 0.2794)
			(stroke
				(width 0.1)
				(type default)
			)
			(layer "F.Fab")
		)
		(fp_line
			(start -0.12065 0.3048)
			(end -0.67945 0.3048)
			(stroke
				(width 0.1)
				(type default)
			)
			(layer "F.Fab")
		)
		(fp_line
			(start -0.67945 0.3048)
			(end -0.67945 -0.305054)
			(stroke
				(width 0.1)
				(type default)
			)
			(layer "F.Fab")
		)
		(pad "1" smd circle
			(at -0.40005 0 90)
			(size 0 0)
			(layers "F.Cu" "F.Mask" "F.Paste")
			(net "P3V3_AUX")
		)
		(pad "2" smd circle
			(at 0.40005 0 90)
			(size 0 0)
			(layers "F.Cu" "F.Mask" "F.Paste")
			(net "GND")
		)
	)
	(footprint ""
		(layer "F.Cu")
		(at 147.271486 -390.398254 -90)
		(property "Reference" "R1845"
			(at 0 0 270)
			(layer "F.SilkS")
			(hide yes)
			(effects
				(font
					(size 1.27 1.27)
				)
			)
		)
		(property "Value" ""
			(at 0 0 270)
			(layer "F.Fab")
			(effects
				(font
					(size 1.27 1.27)
				)
			)
		)
		(duplicate_pad_numbers_are_jumpers no)
		(fp_line
			(start -0.7874 0.4064)
			(end -0.7874 -0.4064)
			(stroke
				(width 0.1524)
				(type default)
			)
			(layer "F.SilkS")
		)
		(fp_line
			(start 0.7874 0.4064)
			(end -0.7874 0.4064)
			(stroke
				(width 0.1524)
				(type default)
			)
			(layer "F.SilkS")
		)
		(fp_line
			(start -0.7874 -0.4064)
			(end 0.7874 -0.4064)
			(stroke
				(width 0.1524)
				(type default)
			)
			(layer "F.SilkS")
		)
		(fp_line
			(start 0.7874 -0.4064)
			(end 0.7874 0.4064)
			(stroke
				(width 0.1524)
				(type default)
			)
			(layer "F.SilkS")
		)
		(fp_line
			(start -0.67945 0.3048)
			(end -0.67945 -0.305054)
			(stroke
				(width 0.1)
				(type default)
			)
			(layer "F.Fab")
		)
		(fp_line
			(start -0.12065 0.3048)
			(end -0.67945 0.3048)
			(stroke
				(width 0.1)
				(type default)
			)
			(layer "F.Fab")
		)
		(fp_line
			(start 0.120396 0.3048)
			(end 0.120396 0.2794)
			(stroke
				(width 0.1)
				(type default)
			)
			(layer "F.Fab")
		)
		(fp_line
			(start 0.67945 0.3048)
			(end 0.120396 0.3048)
			(stroke
				(width 0.1)
				(type default)
			)
			(layer "F.Fab")
		)
		(fp_line
			(start -0.12065 0.2794)
			(end -0.12065 0.3048)
			(stroke
				(width 0.1)
				(type default)
			)
			(layer "F.Fab")
		)
		(fp_line
			(start 0.120396 0.2794)
			(end -0.12065 0.2794)
			(stroke
				(width 0.1)
				(type default)
			)
			(layer "F.Fab")
		)
		(fp_line
			(start -0.12065 -0.2794)
			(end 0.12065 -0.2794)
			(stroke
				(width 0.1)
				(type default)
			)
			(layer "F.Fab")
		)
		(fp_line
			(start 0.12065 -0.2794)
			(end 0.12065 -0.3048)
			(stroke
				(width 0.1)
				(type default)
			)
			(layer "F.Fab")
		)
		(fp_line
			(start 0.12065 -0.3048)
			(end 0.67945 -0.3048)
			(stroke
				(width 0.1)
				(type default)
			)
			(layer "F.Fab")
		)
		(fp_line
			(start 0.67945 -0.3048)
			(end 0.67945 0.3048)
			(stroke
				(width 0.1)
				(type default)
			)
			(layer "F.Fab")
		)
		(fp_line
			(start -0.67945 -0.305054)
			(end -0.12065 -0.305054)
			(stroke
				(width 0.1)
				(type default)
			)
			(layer "F.Fab")
		)
		(fp_line
			(start -0.12065 -0.305054)
			(end -0.12065 -0.2794)
			(stroke
				(width 0.1)
				(type default)
			)
			(layer "F.Fab")
		)
		(pad "1" smd circle
			(at -0.40005 0 270)
			(size 0 0)
			(layers "F.Cu" "F.Mask" "F.Paste")
			(net "SMB_GPU2_ALERT_R_N")
		)
		(pad "2" smd circle
			(at 0.40005 0 270)
			(size 0 0)
			(layers "F.Cu" "F.Mask" "F.Paste")
			(net "SMB_GPU2_ALERT_N")
		)
	)
	(footprint ""
		(layer "F.Cu")
		(at 26.822654 -311.156604 -90)
		(property "Reference" "R1258"
			(at 0 0 270)
			(layer "F.SilkS")
			(hide yes)
			(effects
				(font
					(size 1.27 1.27)
				)
			)
		)
		(property "Value" ""
			(at 0 0 270)
			(layer "F.Fab")
			(effects
				(font
					(size 1.27 1.27)
				)
			)
		)
		(duplicate_pad_numbers_are_jumpers no)
		(fp_line
			(start -0.7874 0.4064)
			(end -0.7874 -0.4064)
			(stroke
				(width 0.1524)
				(type default)
			)
			(layer "F.SilkS")
		)
		(fp_line
			(start 0.7874 0.4064)
			(end -0.7874 0.4064)
			(stroke
				(width 0.1524)
				(type default)
			)
			(layer "F.SilkS")
		)
		(fp_line
			(start -0.7874 -0.4064)
			(end 0.7874 -0.4064)
			(stroke
				(width 0.1524)
				(type default)
			)
			(layer "F.SilkS")
		)
		(fp_line
			(start 0.7874 -0.4064)
			(end 0.7874 0.4064)
			(stroke
				(width 0.1524)
				(type default)
			)
			(layer "F.SilkS")
		)
		(fp_line
			(start -0.67945 0.3048)
			(end -0.67945 -0.305054)
			(stroke
				(width 0.1)
				(type default)
			)
			(layer "F.Fab")
		)
		(fp_line
			(start -0.12065 0.3048)
			(end -0.67945 0.3048)
			(stroke
				(width 0.1)
				(type default)
			)
			(layer "F.Fab")
		)
		(fp_line
			(start 0.120396 0.3048)
			(end 0.120396 0.2794)
			(stroke
				(width 0.1)
				(type default)
			)
			(layer "F.Fab")
		)
		(fp_line
			(start 0.67945 0.3048)
			(end 0.120396 0.3048)
			(stroke
				(width 0.1)
				(type default)
			)
			(layer "F.Fab")
		)
		(fp_line
			(start -0.12065 0.2794)
			(end -0.12065 0.3048)
			(stroke
				(width 0.1)
				(type default)
			)
			(layer "F.Fab")
		)
		(fp_line
			(start 0.120396 0.2794)
			(end -0.12065 0.2794)
			(stroke
				(width 0.1)
				(type default)
			)
			(layer "F.Fab")
		)
		(fp_line
			(start -0.12065 -0.2794)
			(end 0.12065 -0.2794)
			(stroke
				(width 0.1)
				(type default)
			)
			(layer "F.Fab")
		)
		(fp_line
			(start 0.12065 -0.2794)
			(end 0.12065 -0.3048)
			(stroke
				(width 0.1)
				(type default)
			)
			(layer "F.Fab")
		)
		(fp_line
			(start 0.12065 -0.3048)
			(end 0.67945 -0.3048)
			(stroke
				(width 0.1)
				(type default)
			)
			(layer "F.Fab")
		)
		(fp_line
			(start 0.67945 -0.3048)
			(end 0.67945 0.3048)
			(stroke
				(width 0.1)
				(type default)
			)
			(layer "F.Fab")
		)
		(fp_line
			(start -0.67945 -0.305054)
			(end -0.12065 -0.305054)
			(stroke
				(width 0.1)
				(type default)
			)
			(layer "F.Fab")
		)
		(fp_line
			(start -0.12065 -0.305054)
			(end -0.12065 -0.2794)
			(stroke
				(width 0.1)
				(type default)
			)
			(layer "F.Fab")
		)
		(pad "1" smd circle
			(at -0.40005 0 270)
			(size 0 0)
			(layers "F.Cu" "F.Mask" "F.Paste")
			(net "PU_PEX0_TR_TCK")
		)
		(pad "2" smd circle
			(at 0.40005 0 270)
			(size 0 0)
			(layers "F.Cu" "F.Mask" "F.Paste")
			(net "P1V8_PEX")
		)
	)
	(footprint ""
		(layer "F.Cu")
		(at 50.273966 -26.31186 -90)
		(property "Reference" "U399"
			(at 0.04826 -2.356104 90)
			(unlocked yes)
			(layer "F.SilkS")
			(effects
				(font
					(size 0.7874 0.5842)
					(thickness 0.1524)
				)
			)
		)
		(property "Value" ""
			(at 0 0 270)
			(layer "F.Fab")
			(effects
				(font
					(size 1.27 1.27)
				)
			)
		)
		(duplicate_pad_numbers_are_jumpers no)
		(fp_line
			(start -1.949958 1.610106)
			(end -1.949958 -1.610106)
			(stroke
				(width 0.1524)
				(type default)
			)
			(layer "F.SilkS")
		)
		(fp_line
			(start 1.949958 1.610106)
			(end -1.949958 1.610106)
			(stroke
				(width 0.1524)
				(type default)
			)
			(layer "F.SilkS")
		)
		(fp_line
			(start 1.949958 -1.560068)
			(end 1.949958 1.610106)
			(stroke
				(width 0.1524)
				(type default)
			)
			(layer "F.SilkS")
		)
		(fp_line
			(start -1.949958 -1.610106)
			(end 1.949958 -1.610106)
			(stroke
				(width 0.1524)
				(type default)
			)
			(layer "F.SilkS")
		)
		(fp_line
			(start -0.750062 1.560068)
			(end -0.750062 -1.560068)
			(stroke
				(width 0.1)
				(type default)
			)
			(layer "F.Fab")
		)
		(fp_line
			(start 0.750062 1.560068)
			(end -0.750062 1.560068)
			(stroke
				(width 0.1)
				(type default)
			)
			(layer "F.Fab")
		)
		(fp_line
			(start -0.750062 -1.560068)
			(end 0.750062 -1.560068)
			(stroke
				(width 0.1)
				(type default)
			)
			(layer "F.Fab")
		)
		(fp_line
			(start 0.750062 -1.560068)
			(end 0.750062 1.560068)
			(stroke
				(width 0.1)
				(type default)
			)
			(layer "F.Fab")
		)
		(pad "D" smd rect
			(at 1.100074 0 180)
			(size 1.016 1.4224)
			(layers "F.Cu" "F.Mask" "F.Paste")
			(net "SSD1_LED_ISO_N")
		)
		(pad "G" smd rect
			(at -1.100074 -0.94996 180)
			(size 1.016 1.4224)
			(layers "F.Cu" "F.Mask" "F.Paste")
			(net "SSD1_LED_R")
		)
		(pad "S" smd rect
			(at -1.100074 0.94996 180)
			(size 1.016 1.4224)
			(layers "F.Cu" "F.Mask" "F.Paste")
			(net "GND")
		)
	)
	(footprint ""
		(layer "F.Cu")
		(at 389.81634 -350.098614 90)
		(property "Reference" "C758"
			(at 0 0 90)
			(layer "F.SilkS")
			(hide yes)
			(effects
				(font
					(size 1.27 1.27)
				)
			)
		)
		(property "Value" ""
			(at 0 0 90)
			(layer "F.Fab")
			(effects
				(font
					(size 1.27 1.27)
				)
			)
		)
		(duplicate_pad_numbers_are_jumpers no)
		(fp_line
			(start 0.299974 -0.150114)
			(end 0.299974 0.150114)
			(stroke
				(width 0.1)
				(type default)
			)
			(layer "F.Fab")
		)
		(fp_line
			(start -0.299974 -0.150114)
			(end 0.299974 -0.150114)
			(stroke
				(width 0.1)
				(type default)
			)
			(layer "F.Fab")
		)
		(fp_line
			(start 0.299974 0.150114)
			(end -0.299974 0.150114)
			(stroke
				(width 0.1)
				(type default)
			)
			(layer "F.Fab")
		)
		(fp_line
			(start -0.299974 0.150114)
			(end -0.299974 -0.150114)
			(stroke
				(width 0.1)
				(type default)
			)
			(layer "F.Fab")
		)
		(pad "1" smd rect
			(at -0.2667 0 90)
			(size 0.3048 0.381)
			(layers "F.Cu" "F.Mask" "F.Paste")
			(net "P5E_PEX3_STN5_TX_DP<81>")
		)
		(pad "2" smd rect
			(at 0.2667 0 90)
			(size 0.3048 0.381)
			(layers "F.Cu" "F.Mask" "F.Paste")
			(net "P5E_PEX3_STN5_TX_C_DP<81>")
		)
	)
	(footprint ""
		(layer "F.Cu")
		(at 442.403484 -96.811592 90)
		(property "Reference" "R5623"
			(at 0 0 90)
			(layer "F.SilkS")
			(hide yes)
			(effects
				(font
					(size 1.27 1.27)
				)
			)
		)
		(property "Value" ""
			(at 0 0 90)
			(layer "F.Fab")
			(effects
				(font
					(size 1.27 1.27)
				)
			)
		)
		(duplicate_pad_numbers_are_jumpers no)
		(fp_line
			(start 0.7874 -0.4064)
			(end 0.7874 0.4064)
			(stroke
				(width 0.1524)
				(type default)
			)
			(layer "F.SilkS")
		)
		(fp_line
			(start -0.7874 -0.4064)
			(end 0.7874 -0.4064)
			(stroke
				(width 0.1524)
				(type default)
			)
			(layer "F.SilkS")
		)
		(fp_line
			(start 0.7874 0.4064)
			(end -0.7874 0.4064)
			(stroke
				(width 0.1524)
				(type default)
			)
			(layer "F.SilkS")
		)
		(fp_line
			(start -0.7874 0.4064)
			(end -0.7874 -0.4064)
			(stroke
				(width 0.1524)
				(type default)
			)
			(layer "F.SilkS")
		)
		(fp_line
			(start -0.12065 -0.305054)
			(end -0.12065 -0.2794)
			(stroke
				(width 0.1)
				(type default)
			)
			(layer "F.Fab")
		)
		(fp_line
			(start -0.67945 -0.305054)
			(end -0.12065 -0.305054)
			(stroke
				(width 0.1)
				(type default)
			)
			(layer "F.Fab")
		)
		(fp_line
			(start 0.67945 -0.3048)
			(end 0.67945 0.3048)
			(stroke
				(width 0.1)
				(type default)
			)
			(layer "F.Fab")
		)
		(fp_line
			(start 0.12065 -0.3048)
			(end 0.67945 -0.3048)
			(stroke
				(width 0.1)
				(type default)
			)
			(layer "F.Fab")
		)
		(fp_line
			(start 0.12065 -0.2794)
			(end 0.12065 -0.3048)
			(stroke
				(width 0.1)
				(type default)
			)
			(layer "F.Fab")
		)
		(fp_line
			(start -0.12065 -0.2794)
			(end 0.12065 -0.2794)
			(stroke
				(width 0.1)
				(type default)
			)
			(layer "F.Fab")
		)
		(fp_line
			(start 0.120396 0.2794)
			(end -0.12065 0.2794)
			(stroke
				(width 0.1)
				(type default)
			)
			(layer "F.Fab")
		)
		(fp_line
			(start -0.12065 0.2794)
			(end -0.12065 0.3048)
			(stroke
				(width 0.1)
				(type default)
			)
			(layer "F.Fab")
		)
		(fp_line
			(start 0.67945 0.3048)
			(end 0.120396 0.3048)
			(stroke
				(width 0.1)
				(type default)
			)
			(layer "F.Fab")
		)
		(fp_line
			(start 0.120396 0.3048)
			(end 0.120396 0.2794)
			(stroke
				(width 0.1)
				(type default)
			)
			(layer "F.Fab")
		)
		(fp_line
			(start -0.12065 0.3048)
			(end -0.67945 0.3048)
			(stroke
				(width 0.1)
				(type default)
			)
			(layer "F.Fab")
		)
		(fp_line
			(start -0.67945 0.3048)
			(end -0.67945 -0.305054)
			(stroke
				(width 0.1)
				(type default)
			)
			(layer "F.Fab")
		)
		(pad "1" smd circle
			(at -0.40005 0 90)
			(size 0 0)
			(layers "F.Cu" "F.Mask" "F.Paste")
			(net "NIC7_ADC_A0")
		)
		(pad "2" smd circle
			(at 0.40005 0 90)
			(size 0 0)
			(layers "F.Cu" "F.Mask" "F.Paste")
			(net "SMB_NIC7_ADC_SCL")
		)
	)
)
